(kicad_pcb
	(version 20260206)
	(generator "pcbnew")
	(generator_version "10.0")
	(general
		(thickness 1.6)
		(legacy_teardrops no)
	)
	(paper "A4")
	(title_block
		(title "Bryce Canyon_R.DPB_16317-1_OCP.brd")
		(comment 1 "Bryce Canyon / footprints 156-162 of 2099")
	)
	(layers
		(0 "F.Cu" signal "TOP")
		(4 "In1.Cu" signal "L2GND")
		(6 "In2.Cu" signal "L3")
		(8 "In3.Cu" signal "L4VCC")
		(10 "In4.Cu" signal "L5VCC")
		(12 "In5.Cu" signal "L6")
		(14 "In6.Cu" signal "L7GND")
		(2 "B.Cu" signal "BOTTOM")
		(9 "F.Adhes" user "F.Adhesive")
		(11 "B.Adhes" user "B.Adhesive")
		(13 "F.Paste" user "Package Geometry/Pastemask Top")
		(15 "B.Paste" user "Package Geometry/Pastemask Bottom")
		(5 "F.SilkS" user "Ref Des/Silkscreen Top")
		(7 "B.SilkS" user "Ref Des/Silkscreen Bottom")
		(1 "F.Mask" user "Board Geometry/Soldermask Top")
		(3 "B.Mask" user "Board Geometry/Soldermask Bottom")
		(17 "Dwgs.User" user "User.Drawings")
		(19 "Cmts.User" user "User.Comments")
		(21 "Eco1.User" user "User.Eco1")
		(23 "Eco2.User" user "User.Eco2")
		(25 "Edge.Cuts" user "Board Geometry/Outline")
		(27 "Margin" user)
		(31 "F.CrtYd" user "Package Geometry/Place Bound Top")
		(29 "B.CrtYd" user "Package Geometry/Place Bound Bottom")
		(35 "F.Fab" user "Ref Des/Assembly Top")
		(33 "B.Fab" user "Ref Des/Assembly Bottom")
	)
	(footprint ""
		(layer "F.Cu")
		(at 67.1068 -266.065 90)
		(property "Reference" "R176"
			(at 0 0 90)
			(layer "F.SilkS")
			(hide yes)
			(effects
				(font
					(size 1.27 1.27)
				)
			)
		)
		(property "Value" "220R3F-1-GP"
			(at -0.0254 -2.5146 90)
			(unlocked yes)
			(layer "F.Fab")
			(hide yes)
			(effects
				(font
					(size 1.016 1.016)
					(thickness 0.1524)
				)
			)
		)
		(property "Device Type" "R603H22"
			(at -0.0254 -4.0386 90)
			(unlocked yes)
			(layer "F.Fab")
			(hide yes)
			(effects
				(font
					(size 1.016 1.016)
					(thickness 0.1524)
				)
			)
		)
		(duplicate_pad_numbers_are_jumpers no)
		(fp_line
			(start 0.2032 0)
			(end 0.4826 0)
			(stroke
				(width 0.2032)
				(type default)
			)
			(layer "F.SilkS")
		)
		(fp_line
			(start -0.4826 0)
			(end -0.2032 0)
			(stroke
				(width 0.2032)
				(type default)
			)
			(layer "F.SilkS")
		)
		(fp_rect
			(start -0.5842 1.3335)
			(end 0.5842 -1.3335)
			(stroke
				(width 0)
				(type default)
			)
			(fill no)
			(layer "F.CrtYd")
		)
		(fp_rect
			(start -0.5842 1.3335)
			(end 0.5842 -1.3335)
			(stroke
				(width 0)
				(type default)
			)
			(fill no)
			(layer "F.Fab")
		)
		(pad "1" smd custom
			(at 0 -0.762 90)
			(size 0.2159 0.2159)
			(layers "F.Cu" "F.Mask" "F.Paste")
			(net "HDD_PRSNT_1")
			(options
				(clearance outline)
				(anchor circle)
			)
			(primitives
				(gr_poly
					(pts
						(arc
							(start -0.3302 -0.4318)
							(mid -0.402042 -0.402042)
							(end -0.4318 -0.3302)
						)
						(arc
							(start -0.4318 0.3302)
							(mid -0.402042 0.402042)
							(end -0.3302 0.4318)
						)
						(arc
							(start 0.3302 0.4318)
							(mid 0.402042 0.402042)
							(end 0.4318 0.3302)
						)
						(arc
							(start 0.4318 -0.3302)
							(mid 0.402042 -0.402042)
							(end 0.3302 -0.4318)
						)
					)
					(width 0)
					(fill yes)
				)
			)
		)
		(pad "2" smd custom
			(at 0 0.762 90)
			(size 0.2159 0.2159)
			(layers "F.Cu" "F.Mask" "F.Paste")
			(net "DRIVE_B_1_INS")
			(options
				(clearance outline)
				(anchor circle)
			)
			(primitives
				(gr_poly
					(pts
						(arc
							(start -0.3302 -0.4318)
							(mid -0.402042 -0.402042)
							(end -0.4318 -0.3302)
						)
						(arc
							(start -0.4318 0.3302)
							(mid -0.402042 0.402042)
							(end -0.3302 0.4318)
						)
						(arc
							(start 0.3302 0.4318)
							(mid 0.402042 0.402042)
							(end 0.4318 0.3302)
						)
						(arc
							(start 0.4318 -0.3302)
							(mid 0.402042 -0.402042)
							(end 0.3302 -0.4318)
						)
					)
					(width 0)
					(fill yes)
				)
			)
		)
	)
	(footprint ""
		(layer "F.Cu")
		(at 454.98766 -223.994218 90)
		(property "Reference" "C657"
			(at 0 0 90)
			(layer "F.SilkS")
			(hide yes)
			(effects
				(font
					(size 1.27 1.27)
				)
			)
		)
		(property "Value" "SC10U16V5KX-7-GP-U"
			(at -0.0762 -6.1214 90)
			(unlocked yes)
			(layer "F.Fab")
			(hide yes)
			(effects
				(font
					(size 1.016 1.016)
					(thickness 0.1524)
				)
			)
		)
		(property "Device Type" "C805H58"
			(at -0.0762 -8.1534 90)
			(unlocked yes)
			(layer "F.Fab")
			(hide yes)
			(effects
				(font
					(size 1.016 1.016)
					(thickness 0.1524)
				)
			)
		)
		(duplicate_pad_numbers_are_jumpers no)
		(fp_line
			(start 0.635 0)
			(end -0.635 0)
			(stroke
				(width 0.508)
				(type default)
			)
			(layer "F.SilkS")
		)
		(fp_rect
			(start -0.9652 1.778)
			(end 0.9652 -1.778)
			(stroke
				(width 0)
				(type default)
			)
			(fill no)
			(layer "F.CrtYd")
		)
		(fp_poly
			(pts
				(xy -0.9652 -1.778) (xy 0.9652 -1.778) (xy 0.9652 1.778) (xy -0.9652 1.778)
			)
			(stroke
				(width 0)
				(type default)
			)
			(fill no)
			(layer "F.Fab")
		)
		(pad "1" smd rect
			(at 0 -0.9652 90)
			(size 1.397 1.143)
			(layers "F.Cu" "F.Mask" "F.Paste")
			(net "P12V_B_3_VIN_U33")
		)
		(pad "2" smd rect
			(at 0 0.9652 90)
			(size 1.397 1.143)
			(layers "F.Cu" "F.Mask" "F.Paste")
			(net "GND")
		)
	)
	(footprint ""
		(layer "F.Cu")
		(at 144.653 -131.572)
		(property "Reference" "R455"
			(at 0 0 0)
			(layer "F.SilkS")
			(hide yes)
			(effects
				(font
					(size 1.27 1.27)
				)
			)
		)
		(property "Value" "0R2J-2-GP"
			(at 0.064008 -3.993896 0)
			(unlocked yes)
			(layer "F.Fab")
			(hide yes)
			(effects
				(font
					(size 1.016 1.016)
					(thickness 0.1524)
				)
			)
		)
		(property "Device Type" "R402H16"
			(at 0.064008 -5.517896 0)
			(unlocked yes)
			(layer "F.Fab")
			(hide yes)
			(effects
				(font
					(size 1.016 1.016)
					(thickness 0.1524)
				)
			)
		)
		(duplicate_pad_numbers_are_jumpers no)
		(fp_line
			(start -0.508 -0.9398)
			(end -0.508 0.9398)
			(stroke
				(width 0.1524)
				(type default)
			)
			(layer "F.SilkS")
		)
		(fp_line
			(start 0.508 -0.9398)
			(end -0.508 -0.9398)
			(stroke
				(width 0.1524)
				(type default)
			)
			(layer "F.SilkS")
		)
		(fp_rect
			(start -0.508 0.9398)
			(end 0.508 -0.9398)
			(stroke
				(width 0)
				(type default)
			)
			(fill no)
			(layer "F.CrtYd")
		)
		(fp_rect
			(start -0.508 0.9398)
			(end 0.508 -0.9398)
			(stroke
				(width 0)
				(type default)
			)
			(fill no)
			(layer "F.Fab")
		)
		(pad "1" smd custom
			(at 0 -0.4445)
			(size 0.1397 0.1397)
			(layers "F.Cu" "F.Mask" "F.Paste")
			(net "SW_HDD_G16")
			(options
				(clearance outline)
				(anchor circle)
			)
			(primitives
				(gr_poly
					(pts
						(arc
							(start -0.1778 -0.2794)
							(mid -0.249642 -0.249642)
							(end -0.2794 -0.1778)
						)
						(arc
							(start -0.2794 0.1778)
							(mid -0.249642 0.249642)
							(end -0.1778 0.2794)
						)
						(arc
							(start 0.1778 0.2794)
							(mid 0.249642 0.249642)
							(end 0.2794 0.1778)
						)
						(arc
							(start 0.2794 -0.1778)
							(mid 0.249642 -0.249642)
							(end 0.1778 -0.2794)
						)
					)
					(width 0)
					(fill yes)
				)
			)
		)
		(pad "2" smd custom
			(at 0 0.4445)
			(size 0.1397 0.1397)
			(layers "F.Cu" "F.Mask" "F.Paste")
			(net "SW_HDD_R16")
			(options
				(clearance outline)
				(anchor circle)
			)
			(primitives
				(gr_poly
					(pts
						(arc
							(start -0.1778 -0.2794)
							(mid -0.249642 -0.249642)
							(end -0.2794 -0.1778)
						)
						(arc
							(start -0.2794 0.1778)
							(mid -0.249642 0.249642)
							(end -0.1778 0.2794)
						)
						(arc
							(start 0.1778 0.2794)
							(mid 0.249642 0.249642)
							(end 0.2794 0.1778)
						)
						(arc
							(start 0.2794 -0.1778)
							(mid 0.249642 -0.249642)
							(end 0.1778 -0.2794)
						)
					)
					(width 0)
					(fill yes)
				)
			)
		)
	)
	(footprint ""
		(layer "F.Cu")
		(at 318.2112 -262.8138 180)
		(property "Reference" "R257"
			(at 0 0 180)
			(layer "F.SilkS")
			(hide yes)
			(effects
				(font
					(size 1.27 1.27)
				)
			)
		)
		(property "Value" "220R3F-1-GP"
			(at -0.0254 -2.5146 180)
			(unlocked yes)
			(layer "F.Fab")
			(hide yes)
			(effects
				(font
					(size 1.016 1.016)
					(thickness 0.1524)
				)
			)
		)
		(property "Device Type" "R603H22"
			(at -0.0254 -4.0386 180)
			(unlocked yes)
			(layer "F.Fab")
			(hide yes)
			(effects
				(font
					(size 1.016 1.016)
					(thickness 0.1524)
				)
			)
		)
		(duplicate_pad_numbers_are_jumpers no)
		(fp_line
			(start 0.2032 0)
			(end 0.4826 0)
			(stroke
				(width 0.2032)
				(type default)
			)
			(layer "F.SilkS")
		)
		(fp_line
			(start -0.4826 0)
			(end -0.2032 0)
			(stroke
				(width 0.2032)
				(type default)
			)
			(layer "F.SilkS")
		)
		(fp_rect
			(start -0.5842 1.3335)
			(end 0.5842 -1.3335)
			(stroke
				(width 0)
				(type default)
			)
			(fill no)
			(layer "F.CrtYd")
		)
		(fp_rect
			(start -0.5842 1.3335)
			(end 0.5842 -1.3335)
			(stroke
				(width 0)
				(type default)
			)
			(fill no)
			(layer "F.Fab")
		)
		(pad "1" smd custom
			(at 0 -0.762 180)
			(size 0.2159 0.2159)
			(layers "F.Cu" "F.Mask" "F.Paste")
			(net "HDD_PRSNT_6")
			(options
				(clearance outline)
				(anchor circle)
			)
			(primitives
				(gr_poly
					(pts
						(arc
							(start -0.3302 -0.4318)
							(mid -0.402042 -0.402042)
							(end -0.4318 -0.3302)
						)
						(arc
							(start -0.4318 0.3302)
							(mid -0.402042 0.402042)
							(end -0.3302 0.4318)
						)
						(arc
							(start 0.3302 0.4318)
							(mid 0.402042 0.402042)
							(end 0.4318 0.3302)
						)
						(arc
							(start 0.4318 -0.3302)
							(mid 0.402042 -0.402042)
							(end 0.3302 -0.4318)
						)
					)
					(width 0)
					(fill yes)
				)
			)
		)
		(pad "2" smd custom
			(at 0 0.762 180)
			(size 0.2159 0.2159)
			(layers "F.Cu" "F.Mask" "F.Paste")
			(net "DRIVE_B_6_INS")
			(options
				(clearance outline)
				(anchor circle)
			)
			(primitives
				(gr_poly
					(pts
						(arc
							(start -0.3302 -0.4318)
							(mid -0.402042 -0.402042)
							(end -0.4318 -0.3302)
						)
						(arc
							(start -0.4318 0.3302)
							(mid -0.402042 0.402042)
							(end -0.3302 0.4318)
						)
						(arc
							(start 0.3302 0.4318)
							(mid 0.402042 0.402042)
							(end 0.4318 0.3302)
						)
						(arc
							(start 0.4318 -0.3302)
							(mid 0.402042 -0.402042)
							(end 0.3302 -0.4318)
						)
					)
					(width 0)
					(fill yes)
				)
			)
		)
	)
	(footprint ""
		(layer "F.Cu")
		(at 175.550068 -65.39992)
		(property "Reference" "LED18"
			(at 0 0 0)
			(layer "F.SilkS")
			(hide yes)
			(effects
				(font
					(size 1.27 1.27)
				)
			)
		)
		(property "Value" "LED-BY-19-GP"
			(at -2.132076 1.414018 0)
			(unlocked yes)
			(layer "F.Fab")
			(hide yes)
			(effects
				(font
					(size 1.016 1.016)
					(thickness 0.1524)
				)
			)
		)
		(property "Device Type" "LED-1615-4PH26"
			(at -2.132076 -0.109982 0)
			(unlocked yes)
			(layer "F.Fab")
			(hide yes)
			(effects
				(font
					(size 1.016 1.016)
					(thickness 0.1524)
				)
			)
		)
		(duplicate_pad_numbers_are_jumpers no)
		(fp_line
			(start -1.2954 0.254)
			(end -1.2954 1.6002)
			(stroke
				(width 0.508)
				(type default)
			)
			(layer "F.SilkS")
		)
		(fp_line
			(start -1.2954 1.6002)
			(end 1.2954 1.6002)
			(stroke
				(width 0.508)
				(type default)
			)
			(layer "F.SilkS")
		)
		(fp_line
			(start -1.1176 -1.4224)
			(end 1.1176 -1.4224)
			(stroke
				(width 0.1524)
				(type default)
			)
			(layer "F.SilkS")
		)
		(fp_line
			(start -1.1176 1.4224)
			(end -1.1176 -1.4224)
			(stroke
				(width 0.1524)
				(type default)
			)
			(layer "F.SilkS")
		)
		(fp_line
			(start 1.1176 -1.4224)
			(end 1.1176 1.4224)
			(stroke
				(width 0.1524)
				(type default)
			)
			(layer "F.SilkS")
		)
		(fp_line
			(start 1.1176 1.4224)
			(end -1.1176 1.4224)
			(stroke
				(width 0.1524)
				(type default)
			)
			(layer "F.SilkS")
		)
		(fp_line
			(start 1.2954 1.6002)
			(end 1.2954 0.254)
			(stroke
				(width 0.508)
				(type default)
			)
			(layer "F.SilkS")
		)
		(fp_rect
			(start -0.7493 0.8001)
			(end 0.7493 -0.8001)
			(stroke
				(width 0)
				(type default)
			)
			(fill no)
			(layer "F.CrtYd")
		)
		(fp_poly
			(pts
				(xy -1.3716 1.6764) (xy -1.3716 -1.6764) (xy 1.3716 -1.6764) (xy 1.3716 0.0635) (xy 0.7493 0.0635)
				(xy 0.7493 -0.8001) (xy -0.7493 -0.8001) (xy -0.7493 0.8001) (xy 0.7493 0.8001) (xy 0.7493 0.0762)
				(xy 1.3716 0.0762) (xy 1.3716 1.6764)
			)
			(stroke
				(width 0)
				(type default)
			)
			(fill no)
			(layer "F.CrtYd")
		)
		(fp_rect
			(start -1.3716 1.6764)
			(end 1.3716 -1.6764)
			(stroke
				(width 0)
				(type default)
			)
			(fill no)
			(layer "F.Fab")
		)
		(pad "1" smd rect
			(at 0.50038 -0.73025)
			(size 0.7112 0.8636)
			(layers "F.Cu" "F.Mask" "F.Paste")
			(net "DRV_ACT_17")
		)
		(pad "2" smd rect
			(at -0.50038 -0.73025)
			(size 0.7112 0.8636)
			(layers "F.Cu" "F.Mask" "F.Paste")
			(net "FLT_HDD17")
		)
		(pad "3" smd rect
			(at 0.50038 0.73025)
			(size 0.7112 0.8636)
			(layers "F.Cu" "F.Mask" "F.Paste")
			(net "DRV_ACT_17_N")
		)
		(pad "4" smd rect
			(at -0.50038 0.73025)
			(size 0.7112 0.8636)
			(layers "F.Cu" "F.Mask" "F.Paste")
			(net "FLT_HDD17_N")
		)
	)
	(footprint ""
		(layer "F.Cu")
		(at 383.8448 -146.6342 180)
		(property "Reference" "R530"
			(at 0 0 180)
			(layer "F.SilkS")
			(hide yes)
			(effects
				(font
					(size 1.27 1.27)
				)
			)
		)
		(property "Value" "10KR2F-2-GP"
			(at 0.064008 -3.993896 180)
			(unlocked yes)
			(layer "F.Fab")
			(hide yes)
			(effects
				(font
					(size 1.016 1.016)
					(thickness 0.1524)
				)
			)
		)
		(property "Device Type" "R402H16"
			(at 0.064008 -5.517896 180)
			(unlocked yes)
			(layer "F.Fab")
			(hide yes)
			(effects
				(font
					(size 1.016 1.016)
					(thickness 0.1524)
				)
			)
		)
		(duplicate_pad_numbers_are_jumpers no)
		(fp_line
			(start 0.508 -0.9398)
			(end -0.508 -0.9398)
			(stroke
				(width 0.1524)
				(type default)
			)
			(layer "F.SilkS")
		)
		(fp_line
			(start -0.508 -0.9398)
			(end -0.508 0.9398)
			(stroke
				(width 0.1524)
				(type default)
			)
			(layer "F.SilkS")
		)
		(fp_rect
			(start -0.508 0.9398)
			(end 0.508 -0.9398)
			(stroke
				(width 0)
				(type default)
			)
			(fill no)
			(layer "F.CrtYd")
		)
		(fp_rect
			(start -0.508 0.9398)
			(end 0.508 -0.9398)
			(stroke
				(width 0)
				(type default)
			)
			(fill no)
			(layer "F.Fab")
		)
		(pad "1" smd custom
			(at 0 -0.4445 180)
			(size 0.1397 0.1397)
			(layers "F.Cu" "F.Mask" "F.Paste")
			(net "P3V3_STBY_B")
			(options
				(clearance outline)
				(anchor circle)
			)
			(primitives
				(gr_poly
					(pts
						(arc
							(start -0.1778 -0.2794)
							(mid -0.249642 -0.249642)
							(end -0.2794 -0.1778)
						)
						(arc
							(start -0.2794 0.1778)
							(mid -0.249642 0.249642)
							(end -0.1778 0.2794)
						)
						(arc
							(start 0.1778 0.2794)
							(mid 0.249642 0.249642)
							(end 0.2794 0.1778)
						)
						(arc
							(start 0.2794 -0.1778)
							(mid 0.249642 -0.249642)
							(end 0.1778 -0.2794)
						)
					)
					(width 0)
					(fill yes)
				)
			)
		)
		(pad "2" smd custom
			(at 0 0.4445 180)
			(size 0.1397 0.1397)
			(layers "F.Cu" "F.Mask" "F.Paste")
			(net "HDD_PRSNT_20")
			(options
				(clearance outline)
				(anchor circle)
			)
			(primitives
				(gr_poly
					(pts
						(arc
							(start -0.1778 -0.2794)
							(mid -0.249642 -0.249642)
							(end -0.2794 -0.1778)
						)
						(arc
							(start -0.2794 0.1778)
							(mid -0.249642 0.249642)
							(end -0.1778 0.2794)
						)
						(arc
							(start 0.1778 0.2794)
							(mid 0.249642 0.249642)
							(end 0.2794 0.1778)
						)
						(arc
							(start 0.2794 -0.1778)
							(mid 0.249642 -0.249642)
							(end 0.1778 -0.2794)
						)
					)
					(width 0)
					(fill yes)
				)
			)
		)
	)
	(footprint ""
		(layer "F.Cu")
		(at 221.996 -223.139 90)
		(property "Reference" "R22"
			(at 0 0 90)
			(layer "F.SilkS")
			(hide yes)
			(effects
				(font
					(size 1.27 1.27)
				)
			)
		)
		(property "Value" "0R2J-2-GP"
			(at 0.064008 -3.993896 90)
			(unlocked yes)
			(layer "F.Fab")
			(hide yes)
			(effects
				(font
					(size 1.016 1.016)
					(thickness 0.1524)
				)
			)
		)
		(property "Device Type" "R402H16"
			(at 0.064008 -5.517896 90)
			(unlocked yes)
			(layer "F.Fab")
			(hide yes)
			(effects
				(font
					(size 1.016 1.016)
					(thickness 0.1524)
				)
			)
		)
		(duplicate_pad_numbers_are_jumpers no)
		(fp_line
			(start 0.508 -0.9398)
			(end -0.508 -0.9398)
			(stroke
				(width 0.1524)
				(type default)
			)
			(layer "F.SilkS")
		)
		(fp_line
			(start -0.508 -0.9398)
			(end -0.508 0.9398)
			(stroke
				(width 0.1524)
				(type default)
			)
			(layer "F.SilkS")
		)
		(fp_rect
			(start -0.508 0.9398)
			(end 0.508 -0.9398)
			(stroke
				(width 0)
				(type default)
			)
			(fill no)
			(layer "F.CrtYd")
		)
		(fp_rect
			(start -0.508 0.9398)
			(end 0.508 -0.9398)
			(stroke
				(width 0)
				(type default)
			)
			(fill no)
			(layer "F.Fab")
		)
		(pad "1" smd custom
			(at 0 -0.4445 90)
			(size 0.1397 0.1397)
			(layers "F.Cu" "F.Mask" "F.Paste")
			(net "IO_EXP1_LED_SCL")
			(options
				(clearance outline)
				(anchor circle)
			)
			(primitives
				(gr_poly
					(pts
						(arc
							(start -0.1778 -0.2794)
							(mid -0.249642 -0.249642)
							(end -0.2794 -0.1778)
						)
						(arc
							(start -0.2794 0.1778)
							(mid -0.249642 0.249642)
							(end -0.1778 0.2794)
						)
						(arc
							(start 0.1778 0.2794)
							(mid 0.249642 0.249642)
							(end 0.2794 0.1778)
						)
						(arc
							(start 0.2794 -0.1778)
							(mid 0.249642 -0.249642)
							(end 0.1778 -0.2794)
						)
					)
					(width 0)
					(fill yes)
				)
			)
		)
		(pad "2" smd custom
			(at 0 0.4445 90)
			(size 0.1397 0.1397)
			(layers "F.Cu" "F.Mask" "F.Paste")
			(net "I2C_DRIVE_B_FLT_LED_SCL")
			(options
				(clearance outline)
				(anchor circle)
			)
			(primitives
				(gr_poly
					(pts
						(arc
							(start -0.1778 -0.2794)
							(mid -0.249642 -0.249642)
							(end -0.2794 -0.1778)
						)
						(arc
							(start -0.2794 0.1778)
							(mid -0.249642 0.249642)
							(end -0.1778 0.2794)
						)
						(arc
							(start 0.1778 0.2794)
							(mid 0.249642 0.249642)
							(end 0.2794 0.1778)
						)
						(arc
							(start 0.2794 -0.1778)
							(mid 0.249642 -0.249642)
							(end 0.1778 -0.2794)
						)
					)
					(width 0)
					(fill yes)
				)
			)
		)
	)
)
